# T6G (Grand Teton) — schematic netlist excerpt (pin names and nets, part order shuffled) for the footprints in the layout excerpt that follows; sources: Cadence DE-HDL packaged netlist, KiCad conversion of 04192023_DAF0TMB3IC0_F0TG_MB_C_brd_V02_OCP.brd

PL6000  Q_INDUCTOR  3.3UH/6A IND  pkg SMLF  page 269 : \1\ = SW_P1V8_AUX_PH ; \2\ = P1V8_AUX
R3978  Q_RES  100K 1% CHIP  pkg 0402LF  page 146 : A = P3V3_AUX ; B = HP_LVC3_E1S_0_HSC_PWRGD

PL70  Q_INDUCTOR4P_14  150NH IND  pkg L_TLM117513Q-151QL_11X7-5XA  page 196
  \1\  = SW_PVDDCR_CPU0_P0_SW6
  \2\  = IND_CPU0_P0_CPL0
  \3\  = IND_CPU0_P0_CPL6
  \4\  = PVDDCR_CPU0_P0

(kicad_pcb
	(version 20260206)
	(generator "pcbnew")
	(generator_version "10.0")
	(general
		(thickness 1.6)
		(legacy_teardrops no)
	)
	(paper "A4")
	(title_block
		(title "04192023_DAF0TMB3IC0_F0TG_MB_C_brd_V02_OCP.brd")
		(comment 1 "Grand Teton / footprints 3585-3587 of 8354")
	)
	(layers
		(0 "F.Cu" signal "TOP")
		(4 "In1.Cu" signal "GND")
		(6 "In2.Cu" signal "IN1")
		(8 "In3.Cu" signal "GND1")
		(10 "In4.Cu" signal "IN2")
		(12 "In5.Cu" signal "GND2")
		(14 "In6.Cu" signal "IN3")
		(16 "In7.Cu" signal "GND3")
		(18 "In8.Cu" signal "VCC")
		(20 "In9.Cu" signal "VCC1")
		(22 "In10.Cu" signal "GND4")
		(24 "In11.Cu" signal "IN4")
		(26 "In12.Cu" signal "GND5")
		(28 "In13.Cu" signal "IN5")
		(30 "In14.Cu" signal "GND6")
		(32 "In15.Cu" signal "IN6")
		(34 "In16.Cu" signal "GND7")
		(2 "B.Cu" signal "BOTTOM")
		(9 "F.Adhes" user "F.Adhesive")
		(11 "B.Adhes" user "B.Adhesive")
		(13 "F.Paste" user "Package Geometry/Pastemask Top")
		(15 "B.Paste" user "Package Geometry/Pastemask Bottom")
		(5 "F.SilkS" user "Ref Des/Silkscreen Top")
		(7 "B.SilkS" user "Ref Des/Silkscreen Bottom")
		(1 "F.Mask" user "Board Geometry/Soldermask Top")
		(3 "B.Mask" user "Board Geometry/Soldermask Bottom")
		(17 "Dwgs.User" user "User.Drawings")
		(19 "Cmts.User" user "User.Comments")
		(21 "Eco1.User" user "User.Eco1")
		(23 "Eco2.User" user "User.Eco2")
		(25 "Edge.Cuts" user "Board Geometry/Outline")
		(27 "Margin" user)
		(31 "F.CrtYd" user "Package Geometry/Place Bound Top")
		(29 "B.CrtYd" user "Package Geometry/Place Bound Bottom")
		(35 "F.Fab" user "Ref Des/Assembly Top")
		(33 "B.Fab" user "Ref Des/Assembly Bottom")
	)
	(footprint ""
		(layer "F.Cu")
		(at 347.690694 -170.457114 180)
		(property "Reference" "PL70"
			(at 3.709924 7.921498 0)
			(unlocked yes)
			(layer "F.SilkS")
			(effects
				(font
					(size 0.7874 0.5842)
					(thickness 0.1524)
				)
				(justify left)
			)
		)
		(property "Value" ""
			(at 0 0 180)
			(layer "F.Fab")
			(effects
				(font
					(size 1.27 1.27)
				)
			)
		)
		(duplicate_pad_numbers_are_jumpers no)
		(fp_line
			(start 3.750056 5.500116)
			(end 3.750056 -5.500116)
			(stroke
				(width 0.1524)
				(type default)
			)
			(layer "F.SilkS")
		)
		(fp_line
			(start 3.750056 -5.500116)
			(end 2.393442 -5.500116)
			(stroke
				(width 0.1524)
				(type default)
			)
			(layer "F.SilkS")
		)
		(fp_line
			(start 2.393442 5.500116)
			(end 3.750056 5.500116)
			(stroke
				(width 0.1524)
				(type default)
			)
			(layer "F.SilkS")
		)
		(fp_line
			(start -2.393442 5.500116)
			(end -3.750056 5.500116)
			(stroke
				(width 0.1524)
				(type default)
			)
			(layer "F.SilkS")
		)
		(fp_line
			(start -3.750056 5.500116)
			(end -3.750056 -5.500116)
			(stroke
				(width 0.1524)
				(type default)
			)
			(layer "F.SilkS")
		)
		(fp_line
			(start -3.750056 -5.500116)
			(end -2.393442 -5.500116)
			(stroke
				(width 0.1524)
				(type default)
			)
			(layer "F.SilkS")
		)
		(fp_poly
			(pts
				(xy -3.962908 -5.305044) (xy -4.978908 -4.797044) (xy -4.978908 -5.813044)
			)
			(stroke
				(width 0)
				(type default)
			)
			(fill yes)
			(layer "F.SilkS")
		)
		(fp_line
			(start 3.750056 5.500116)
			(end 3.750056 -5.500116)
			(stroke
				(width 0.1)
				(type default)
			)
			(layer "F.Fab")
		)
		(fp_line
			(start 3.750056 -5.500116)
			(end -3.750056 -5.500116)
			(stroke
				(width 0.1)
				(type default)
			)
			(layer "F.Fab")
		)
		(fp_line
			(start -3.750056 5.500116)
			(end 3.750056 5.500116)
			(stroke
				(width 0.1)
				(type default)
			)
			(layer "F.Fab")
		)
		(fp_line
			(start -3.750056 -5.500116)
			(end -3.750056 5.500116)
			(stroke
				(width 0.1)
				(type default)
			)
			(layer "F.Fab")
		)
		(fp_poly
			(pts
				(xy -4.9276 -4.757928) (xy -4.9276 -3.741928) (xy -3.9116 -4.249928)
			)
			(stroke
				(width 0)
				(type default)
			)
			(fill yes)
			(layer "F.Fab")
		)
		(pad "1" smd rect
			(at 0 -4.249928 90)
			(size 2.413 4.5212)
			(layers "F.Cu" "F.Mask" "F.Paste")
			(net "SW_PVDDCR_CPU0_P0_SW6")
		)
		(pad "2" smd rect
			(at 0 -1.175004 90)
			(size 1.3716 4.5212)
			(layers "F.Cu" "F.Mask" "F.Paste")
			(net "IND_CPU0_P0_CPL0")
		)
		(pad "3" smd rect
			(at 0 1.175004 90)
			(size 1.3716 4.5212)
			(layers "F.Cu" "F.Mask" "F.Paste")
			(net "IND_CPU0_P0_CPL6")
		)
		(pad "4" smd rect
			(at 0 4.249928 90)
			(size 2.413 4.5212)
			(layers "F.Cu" "F.Mask" "F.Paste")
			(net "PVDDCR_CPU0_P0")
		)
	)
	(footprint ""
		(layer "F.Cu")
		(at 252.222 -38.683946 180)
		(property "Reference" "R3978"
			(at 0 0 180)
			(layer "F.SilkS")
			(hide yes)
			(effects
				(font
					(size 1.27 1.27)
				)
			)
		)
		(property "Value" ""
			(at 0 0 180)
			(layer "F.Fab")
			(effects
				(font
					(size 1.27 1.27)
				)
			)
		)
		(duplicate_pad_numbers_are_jumpers no)
		(fp_line
			(start 0.7874 0.4064)
			(end -0.7874 0.4064)
			(stroke
				(width 0.1524)
				(type default)
			)
			(layer "F.SilkS")
		)
		(fp_line
			(start 0.7874 -0.4064)
			(end 0.7874 0.4064)
			(stroke
				(width 0.1524)
				(type default)
			)
			(layer "F.SilkS")
		)
		(fp_line
			(start -0.7874 0.4064)
			(end -0.7874 -0.4064)
			(stroke
				(width 0.1524)
				(type default)
			)
			(layer "F.SilkS")
		)
		(fp_line
			(start -0.7874 -0.4064)
			(end 0.7874 -0.4064)
			(stroke
				(width 0.1524)
				(type default)
			)
			(layer "F.SilkS")
		)
		(fp_line
			(start 0.67945 0.3048)
			(end 0.120396 0.3048)
			(stroke
				(width 0.1)
				(type default)
			)
			(layer "F.Fab")
		)
		(fp_line
			(start 0.67945 -0.3048)
			(end 0.67945 0.3048)
			(stroke
				(width 0.1)
				(type default)
			)
			(layer "F.Fab")
		)
		(fp_line
			(start 0.12065 -0.2794)
			(end 0.12065 -0.3048)
			(stroke
				(width 0.1)
				(type default)
			)
			(layer "F.Fab")
		)
		(fp_line
			(start 0.12065 -0.3048)
			(end 0.67945 -0.3048)
			(stroke
				(width 0.1)
				(type default)
			)
			(layer "F.Fab")
		)
		(fp_line
			(start 0.120396 0.3048)
			(end 0.120396 0.2794)
			(stroke
				(width 0.1)
				(type default)
			)
			(layer "F.Fab")
		)
		(fp_line
			(start 0.120396 0.2794)
			(end -0.12065 0.2794)
			(stroke
				(width 0.1)
				(type default)
			)
			(layer "F.Fab")
		)
		(fp_line
			(start -0.12065 0.3048)
			(end -0.67945 0.3048)
			(stroke
				(width 0.1)
				(type default)
			)
			(layer "F.Fab")
		)
		(fp_line
			(start -0.12065 0.2794)
			(end -0.12065 0.3048)
			(stroke
				(width 0.1)
				(type default)
			)
			(layer "F.Fab")
		)
		(fp_line
			(start -0.12065 -0.2794)
			(end 0.12065 -0.2794)
			(stroke
				(width 0.1)
				(type default)
			)
			(layer "F.Fab")
		)
		(fp_line
			(start -0.12065 -0.305054)
			(end -0.12065 -0.2794)
			(stroke
				(width 0.1)
				(type default)
			)
			(layer "F.Fab")
		)
		(fp_line
			(start -0.67945 0.3048)
			(end -0.67945 -0.305054)
			(stroke
				(width 0.1)
				(type default)
			)
			(layer "F.Fab")
		)
		(fp_line
			(start -0.67945 -0.305054)
			(end -0.12065 -0.305054)
			(stroke
				(width 0.1)
				(type default)
			)
			(layer "F.Fab")
		)
		(pad "1" smd circle
			(at -0.40005 0 180)
			(size 0 0)
			(layers "F.Cu" "F.Mask" "F.Paste")
			(net "P3V3_AUX")
		)
		(pad "2" smd circle
			(at 0.40005 0 180)
			(size 0 0)
			(layers "F.Cu" "F.Mask" "F.Paste")
			(net "HP_LVC3_E1S_0_HSC_PWRGD")
		)
	)
	(footprint ""
		(layer "F.Cu")
		(at 151.182832 -77.752956)
		(property "Reference" "PL6000"
			(at -5.397754 -4.964684 0)
			(unlocked yes)
			(layer "F.SilkS")
			(effects
				(font
					(size 0.7874 0.5842)
					(thickness 0.1524)
				)
				(justify left)
			)
		)
		(property "Value" ""
			(at 0 0 0)
			(layer "F.Fab")
			(effects
				(font
					(size 1.27 1.27)
				)
			)
		)
		(duplicate_pad_numbers_are_jumpers no)
		(fp_line
			(start -3.6576 -3.350006)
			(end 3.64998 -3.350006)
			(stroke
				(width 0.1524)
				(type default)
			)
			(layer "F.SilkS")
		)
		(fp_line
			(start -3.64998 -1.8034)
			(end -3.64998 -3.350006)
			(stroke
				(width 0.1524)
				(type default)
			)
			(layer "F.SilkS")
		)
		(fp_line
			(start -3.64998 3.350006)
			(end -3.64998 1.8288)
			(stroke
				(width 0.1524)
				(type default)
			)
			(layer "F.SilkS")
		)
		(fp_line
			(start 3.64998 -3.350006)
			(end 3.64998 -1.8034)
			(stroke
				(width 0.1524)
				(type default)
			)
			(layer "F.SilkS")
		)
		(fp_line
			(start 3.64998 1.8034)
			(end 3.64998 3.350006)
			(stroke
				(width 0.1524)
				(type default)
			)
			(layer "F.SilkS")
		)
		(fp_line
			(start 3.64998 3.350006)
			(end -3.64998 3.350006)
			(stroke
				(width 0.1524)
				(type default)
			)
			(layer "F.SilkS")
		)
		(fp_line
			(start -3.64998 -3.350006)
			(end 3.64998 -3.350006)
			(stroke
				(width 0.1)
				(type default)
			)
			(layer "F.Fab")
		)
		(fp_line
			(start -3.64998 3.350006)
			(end -3.64998 -3.350006)
			(stroke
				(width 0.1)
				(type default)
			)
			(layer "F.Fab")
		)
		(fp_line
			(start 3.64998 -3.350006)
			(end 3.64998 3.350006)
			(stroke
				(width 0.1)
				(type default)
			)
			(layer "F.Fab")
		)
		(fp_line
			(start 3.64998 3.350006)
			(end -3.64998 3.350006)
			(stroke
				(width 0.1)
				(type default)
			)
			(layer "F.Fab")
		)
		(pad "1" smd rect
			(at -2.92481 0)
			(size 2.15392 3.302)
			(layers "F.Cu" "F.Mask" "F.Paste")
			(net "SW_P1V8_AUX_PH")
		)
		(pad "2" smd rect
			(at 2.92481 0)
			(size 2.15392 3.302)
			(layers "F.Cu" "F.Mask" "F.Paste")
			(net "P1V8_AUX")
		)
	)
)
